(kicad_pcb
	(version 20260206)
	(generator "pcbnew")
	(generator_version "10.0")
	(general
		(thickness 1.6)
		(legacy_teardrops no)
	)
	(paper "A4")
	(title_block
		(title "fcb — Lightning_FCB_BRD.brd")
		(comment 1 "Lightning (Wiwynn / Facebook NVMe JBOF) / footprints 469-473 of 495")
	)
	(layers
		(0 "F.Cu" signal "TOP")
		(4 "In1.Cu" signal "L2GND")
		(6 "In2.Cu" signal "L3VCC")
		(2 "B.Cu" signal "BOTTOM")
		(9 "F.Adhes" user "F.Adhesive")
		(11 "B.Adhes" user "B.Adhesive")
		(13 "F.Paste" user "Package Geometry/Pastemask Top")
		(15 "B.Paste" user "Package Geometry/Pastemask Bottom")
		(5 "F.SilkS" user "Ref Des/Silkscreen Top")
		(7 "B.SilkS" user "Ref Des/Silkscreen Bottom")
		(1 "F.Mask" user "Board Geometry/Soldermask Top")
		(3 "B.Mask" user "Board Geometry/Soldermask Bottom")
		(17 "Dwgs.User" user "User.Drawings")
		(19 "Cmts.User" user "User.Comments")
		(21 "Eco1.User" user "User.Eco1")
		(23 "Eco2.User" user "User.Eco2")
		(25 "Edge.Cuts" user "Board Geometry/Outline")
		(27 "Margin" user)
		(31 "F.CrtYd" user "Package Geometry/Place Bound Top")
		(29 "B.CrtYd" user "Package Geometry/Place Bound Bottom")
		(35 "F.Fab" user "Ref Des/Assembly Top")
		(33 "B.Fab" user "Ref Des/Assembly Bottom")
	)
	(footprint ""
		(layer "F.Cu")
		(at 27.559 -217.780616)
		(property "Reference" "U7"
			(at 0 0 0)
			(layer "F.SilkS")
			(hide yes)
			(effects
				(font
					(size 1.27 1.27)
				)
			)
		)
		(property "Value" "TSLV07APWR-GP"
			(at -7.112 -6.0579 0)
			(unlocked yes)
			(layer "F.Fab")
			(hide yes)
			(effects
				(font
					(size 1.016 1.016)
					(thickness 0.1524)
				)
			)
		)
		(property "Device Type" "TSOIC14H48"
			(at -7.112 -7.5819 0)
			(unlocked yes)
			(layer "F.Fab")
			(hide yes)
			(effects
				(font
					(size 1.016 1.016)
					(thickness 0.1524)
				)
			)
		)
		(duplicate_pad_numbers_are_jumpers no)
		(fp_line
			(start -2.9718 -1.778)
			(end 2.1336 -1.778)
			(stroke
				(width 0.1524)
				(type default)
			)
			(layer "F.SilkS")
		)
		(fp_line
			(start -2.9718 1.778)
			(end -2.9718 -1.778)
			(stroke
				(width 0.1524)
				(type default)
			)
			(layer "F.SilkS")
		)
		(fp_line
			(start -2.9337 -0.4699)
			(end -2.9083 -0.4699)
			(stroke
				(width 0.1524)
				(type default)
			)
			(layer "F.SilkS")
		)
		(fp_line
			(start -2.9083 -0.4699)
			(end -2.4384 0)
			(stroke
				(width 0.1524)
				(type default)
			)
			(layer "F.SilkS")
		)
		(fp_line
			(start -2.8956 0.4572)
			(end -2.921 0.4572)
			(stroke
				(width 0.1524)
				(type default)
			)
			(layer "F.SilkS")
		)
		(fp_line
			(start -2.794 3.8227)
			(end -2.794 1.7018)
			(stroke
				(width 0.508)
				(type default)
			)
			(layer "F.SilkS")
		)
		(fp_line
			(start -2.4384 0)
			(end -2.8956 0.4572)
			(stroke
				(width 0.1524)
				(type default)
			)
			(layer "F.SilkS")
		)
		(fp_line
			(start 2.1336 -1.778)
			(end 2.1336 1.778)
			(stroke
				(width 0.1524)
				(type default)
			)
			(layer "F.SilkS")
		)
		(fp_line
			(start 2.1336 1.778)
			(end -2.9718 1.778)
			(stroke
				(width 0.1524)
				(type default)
			)
			(layer "F.SilkS")
		)
		(fp_poly
			(pts
				(xy -2.1336 -1.7653) (xy 2.1336 -1.7653) (xy 2.1336 1.778) (xy -2.1336 1.778)
			)
			(stroke
				(width 0)
				(type default)
			)
			(fill yes)
			(layer "F.SilkS")
		)
		(fp_rect
			(start -2.5019 3.2004)
			(end 2.5019 -3.2004)
			(stroke
				(width 0)
				(type default)
			)
			(fill no)
			(layer "F.CrtYd")
		)
		(fp_poly
			(pts
				(xy -3.048 4.0894) (xy -3.048 -2.5781) (xy -2.5019 -2.5781) (xy -2.5019 3.2004) (xy 2.5019 3.2004)
				(xy 2.5019 -3.2004) (xy -2.5019 -3.2004) (xy -2.5019 -2.5908) (xy -3.048 -2.5908) (xy -3.048 -4.0894)
				(xy 3.048 -4.0894) (xy 3.048 4.0894)
			)
			(stroke
				(width 0)
				(type default)
			)
			(fill no)
			(layer "F.CrtYd")
		)
		(fp_rect
			(start -3.048 4.0894)
			(end 3.048 -4.0894)
			(stroke
				(width 0)
				(type default)
			)
			(fill no)
			(layer "F.Fab")
		)
		(pad "1" smd rect
			(at -1.94945 2.8194)
			(size 0.3556 1.524)
			(layers "F.Cu" "F.Mask" "F.Paste")
			(net "PWM_BUFFER_IN_FAN5_FAN6")
		)
		(pad "2" smd rect
			(at -1.30048 2.8194)
			(size 0.3556 1.524)
			(layers "F.Cu" "F.Mask" "F.Paste")
			(net "PWM_OUT_FAN6")
		)
		(pad "3" smd rect
			(at -0.65024 2.8194)
			(size 0.3556 1.524)
			(layers "F.Cu" "F.Mask" "F.Paste")
			(net "PWM_BUFFER_IN_FAN5_FAN6")
		)
		(pad "4" smd rect
			(at 0 2.8194)
			(size 0.3556 1.524)
			(layers "F.Cu" "F.Mask" "F.Paste")
			(net "PWM_OUT_FAN5")
		)
		(pad "5" smd rect
			(at 0.65024 2.8194)
			(size 0.3556 1.524)
			(layers "F.Cu" "F.Mask" "F.Paste")
			(net "PWM_BUFFER_IN_FAN3_FAN4")
		)
		(pad "6" smd rect
			(at 1.30048 2.8194)
			(size 0.3556 1.524)
			(layers "F.Cu" "F.Mask" "F.Paste")
			(net "PWM_OUT_FAN4")
		)
		(pad "7" smd rect
			(at 1.94945 2.8194)
			(size 0.3556 1.524)
			(layers "F.Cu" "F.Mask" "F.Paste")
			(net "GND")
		)
		(pad "8" smd rect
			(at 1.94945 -2.8194)
			(size 0.3556 1.524)
			(layers "F.Cu" "F.Mask" "F.Paste")
			(net "PWM_OUT_FAN3")
		)
		(pad "9" smd rect
			(at 1.30048 -2.8194)
			(size 0.3556 1.524)
			(layers "F.Cu" "F.Mask" "F.Paste")
			(net "PWM_BUFFER_IN_FAN3_FAN4")
		)
		(pad "10" smd rect
			(at 0.65024 -2.8194)
			(size 0.3556 1.524)
			(layers "F.Cu" "F.Mask" "F.Paste")
			(net "PWM_OUT_FAN2")
		)
		(pad "11" smd rect
			(at 0 -2.8194)
			(size 0.3556 1.524)
			(layers "F.Cu" "F.Mask" "F.Paste")
			(net "PWM_BUFFER_IN_FAN1_FAN2")
		)
		(pad "12" smd rect
			(at -0.65024 -2.8194)
			(size 0.3556 1.524)
			(layers "F.Cu" "F.Mask" "F.Paste")
			(net "PWM_OUT_FAN1")
		)
		(pad "13" smd rect
			(at -1.30048 -2.8194)
			(size 0.3556 1.524)
			(layers "F.Cu" "F.Mask" "F.Paste")
			(net "PWM_BUFFER_IN_FAN1_FAN2")
		)
		(pad "14" smd rect
			(at -1.94945 -2.8194)
			(size 0.3556 1.524)
			(layers "F.Cu" "F.Mask" "F.Paste")
			(net "P3V3")
		)
	)
	(footprint ""
		(layer "F.Cu")
		(at 10.5664 -447.2686)
		(property "Reference" "D12"
			(at 0 0 0)
			(layer "F.SilkS")
			(hide yes)
			(effects
				(font
					(size 1.27 1.27)
				)
			)
		)
		(property "Value" "BAS16H-GP"
			(at 0 -5.5372 0)
			(unlocked yes)
			(layer "F.Fab")
			(hide yes)
			(effects
				(font
					(size 1.016 1.016)
					(thickness 0.1524)
				)
			)
		)
		(property "Device Type" "SOD123AKH48"
			(at 0 -7.0612 0)
			(unlocked yes)
			(layer "F.Fab")
			(hide yes)
			(effects
				(font
					(size 1.016 1.016)
					(thickness 0.1524)
				)
			)
		)
		(duplicate_pad_numbers_are_jumpers no)
		(fp_line
			(start -1.016 -2.667)
			(end -1.016 2.667)
			(stroke
				(width 0.1524)
				(type default)
			)
			(layer "F.SilkS")
		)
		(fp_line
			(start -1.016 2.667)
			(end 1.016 2.667)
			(stroke
				(width 0.1524)
				(type default)
			)
			(layer "F.SilkS")
		)
		(fp_line
			(start 0.889 2.921)
			(end -0.889 2.921)
			(stroke
				(width 0.508)
				(type default)
			)
			(layer "F.SilkS")
		)
		(fp_line
			(start 1.016 -2.667)
			(end -1.016 -2.667)
			(stroke
				(width 0.1524)
				(type default)
			)
			(layer "F.SilkS")
		)
		(fp_line
			(start 1.016 2.667)
			(end 1.016 -2.667)
			(stroke
				(width 0.1524)
				(type default)
			)
			(layer "F.SilkS")
		)
		(fp_rect
			(start -1.143 3.175)
			(end 1.143 -2.794)
			(stroke
				(width 0)
				(type default)
			)
			(fill no)
			(layer "F.CrtYd")
		)
		(fp_poly
			(pts
				(xy -1.143 -2.794) (xy 1.143 -2.794) (xy 1.143 3.175) (xy -1.143 3.175)
			)
			(stroke
				(width 0)
				(type default)
			)
			(fill no)
			(layer "F.Fab")
		)
		(pad "A" smd rect
			(at 0 -1.6891)
			(size 0.889 1.397)
			(layers "F.Cu" "F.Mask" "F.Paste")
			(net "FAN_TACH2")
		)
		(pad "K" smd rect
			(at 0 1.6891)
			(size 0.889 1.397)
			(layers "F.Cu" "F.Mask" "F.Paste")
			(net "P12V")
		)
	)
	(footprint ""
		(layer "F.Cu")
		(at 13.5636 -64.2112 -90)
		(property "Reference" "C56"
			(at 0 0 270)
			(layer "F.SilkS")
			(hide yes)
			(effects
				(font
					(size 1.27 1.27)
				)
			)
		)
		(property "Value" "SC220P50V3JN-GP"
			(at 0 -2.8194 270)
			(unlocked yes)
			(layer "F.Fab")
			(hide yes)
			(effects
				(font
					(size 1.016 1.016)
					(thickness 0.1524)
				)
			)
		)
		(property "Device Type" "C603H36"
			(at 0 -4.3434 270)
			(unlocked yes)
			(layer "F.Fab")
			(hide yes)
			(effects
				(font
					(size 1.016 1.016)
					(thickness 0.1524)
				)
			)
		)
		(duplicate_pad_numbers_are_jumpers no)
		(fp_line
			(start 0.508 0)
			(end -0.508 0)
			(stroke
				(width 0.2032)
				(type default)
			)
			(layer "F.SilkS")
		)
		(fp_rect
			(start -0.5842 1.3335)
			(end 0.5842 -1.3335)
			(stroke
				(width 0)
				(type default)
			)
			(fill no)
			(layer "F.CrtYd")
		)
		(fp_rect
			(start -0.5842 1.3335)
			(end 0.5842 -1.3335)
			(stroke
				(width 0)
				(type default)
			)
			(fill no)
			(layer "F.Fab")
		)
		(pad "1" smd custom
			(at 0 -0.762 270)
			(size 0.2159 0.2159)
			(layers "F.Cu" "F.Mask" "F.Paste")
			(net "I2C_C_SCL_CONN_R")
			(options
				(clearance outline)
				(anchor circle)
			)
			(primitives
				(gr_poly
					(pts
						(arc
							(start -0.3302 -0.4318)
							(mid -0.402042 -0.402042)
							(end -0.4318 -0.3302)
						)
						(arc
							(start -0.4318 0.3302)
							(mid -0.402042 0.402042)
							(end -0.3302 0.4318)
						)
						(arc
							(start 0.3302 0.4318)
							(mid 0.402042 0.402042)
							(end 0.4318 0.3302)
						)
						(arc
							(start 0.4318 -0.3302)
							(mid 0.402042 -0.402042)
							(end 0.3302 -0.4318)
						)
					)
					(width 0)
					(fill yes)
				)
			)
		)
		(pad "2" smd custom
			(at 0 0.762 270)
			(size 0.2159 0.2159)
			(layers "F.Cu" "F.Mask" "F.Paste")
			(net "GND")
			(options
				(clearance outline)
				(anchor circle)
			)
			(primitives
				(gr_poly
					(pts
						(arc
							(start -0.3302 -0.4318)
							(mid -0.402042 -0.402042)
							(end -0.4318 -0.3302)
						)
						(arc
							(start -0.4318 0.3302)
							(mid -0.402042 0.402042)
							(end -0.3302 0.4318)
						)
						(arc
							(start 0.3302 0.4318)
							(mid 0.402042 0.402042)
							(end 0.4318 0.3302)
						)
						(arc
							(start 0.4318 -0.3302)
							(mid 0.402042 -0.402042)
							(end 0.3302 -0.4318)
						)
					)
					(width 0)
					(fill yes)
				)
			)
		)
	)
	(footprint ""
		(layer "F.Cu")
		(at 34.739834 -139.324334 90)
		(property "Reference" "TP24"
			(at 0 0 90)
			(layer "F.SilkS")
			(hide yes)
			(effects
				(font
					(size 1.27 1.27)
				)
			)
		)
		(property "Value" "TPAD32-GP"
			(at 0 -3.166364 90)
			(unlocked yes)
			(layer "F.Fab")
			(hide yes)
			(effects
				(font
					(size 1.016 1.016)
					(thickness 0.1524)
				)
			)
		)
		(property "Device Type" "TPAD32"
			(at 0 -4.690618 90)
			(unlocked yes)
			(layer "F.Fab")
			(hide yes)
			(effects
				(font
					(size 1.016 1.016)
					(thickness 0.1524)
				)
			)
		)
		(duplicate_pad_numbers_are_jumpers no)
		(fp_poly
			(pts
				(arc
					(start 0 0.7112)
					(mid 0 -0.7112)
					(end 0 0.7112)
				)
			)
			(stroke
				(width 0)
				(type default)
			)
			(fill no)
			(layer "F.CrtYd")
		)
		(fp_poly
			(pts
				(arc
					(start 0 0.7112)
					(mid 0 -0.7112)
					(end 0 0.7112)
				)
			)
			(stroke
				(width 0)
				(type default)
			)
			(fill no)
			(layer "F.Fab")
		)
		(pad "1" smd circle
			(at 0 0 90)
			(size 0.8128 0.8128)
			(layers "F.Cu" "F.Mask" "F.Paste")
			(net "P12VL_2490_PG")
		)
	)
	(footprint ""
		(layer "F.Cu")
		(at 38.5826 -356.921816)
		(property "Reference" "PQ14"
			(at 0 0 0)
			(layer "F.SilkS")
			(hide yes)
			(effects
				(font
					(size 1.27 1.27)
				)
			)
		)
		(property "Value" "PMBS3904-1-GP"
			(at 0 -9.0932 0)
			(unlocked yes)
			(layer "F.Fab")
			(hide yes)
			(effects
				(font
					(size 1.016 1.016)
					(thickness 0.1524)
				)
			)
		)
		(property "Device Type" "SOT-23-10H44"
			(at 0 -10.6172 0)
			(unlocked yes)
			(layer "F.Fab")
			(hide yes)
			(effects
				(font
					(size 1.016 1.016)
					(thickness 0.1524)
				)
			)
		)
		(duplicate_pad_numbers_are_jumpers no)
		(fp_line
			(start -1.7526 1.8796)
			(end -1.7526 0.9906)
			(stroke
				(width 0.3302)
				(type default)
			)
			(layer "F.SilkS")
		)
		(fp_line
			(start -1.651 -1.778)
			(end -1.651 1.778)
			(stroke
				(width 0.1524)
				(type default)
			)
			(layer "F.SilkS")
		)
		(fp_line
			(start -1.651 1.778)
			(end 1.651 1.778)
			(stroke
				(width 0.1524)
				(type default)
			)
			(layer "F.SilkS")
		)
		(fp_line
			(start -1.279398 2.152142)
			(end -0.9906 1.86309)
			(stroke
				(width 0.0127)
				(type default)
			)
			(layer "F.SilkS")
		)
		(fp_line
			(start -1.279144 2.15265)
			(end -0.701294 2.15265)
			(stroke
				(width 0.0127)
				(type default)
			)
			(layer "F.SilkS")
		)
		(fp_line
			(start -1.260856 2.1336)
			(end -0.720344 2.1336)
			(stroke
				(width 0.0127)
				(type default)
			)
			(layer "F.SilkS")
		)
		(fp_line
			(start -1.251458 2.124202)
			(end -0.729996 2.124202)
			(stroke
				(width 0.0127)
				(type default)
			)
			(layer "F.SilkS")
		)
		(fp_line
			(start -1.241806 2.11455)
			(end -0.739394 2.11455)
			(stroke
				(width 0.0127)
				(type default)
			)
			(layer "F.SilkS")
		)
		(fp_line
			(start -1.232408 2.105152)
			(end -0.749046 2.105152)
			(stroke
				(width 0.0127)
				(type default)
			)
			(layer "F.SilkS")
		)
		(fp_line
			(start -1.222756 2.0955)
			(end -0.758444 2.0955)
			(stroke
				(width 0.0127)
				(type default)
			)
			(layer "F.SilkS")
		)
		(fp_line
			(start -1.213358 2.086102)
			(end -0.768096 2.086102)
			(stroke
				(width 0.0127)
				(type default)
			)
			(layer "F.SilkS")
		)
		(fp_line
			(start -1.203706 2.07645)
			(end -0.777494 2.07645)
			(stroke
				(width 0.0127)
				(type default)
			)
			(layer "F.SilkS")
		)
		(fp_line
			(start -1.194308 2.067052)
			(end -0.787146 2.067052)
			(stroke
				(width 0.0127)
				(type default)
			)
			(layer "F.SilkS")
		)
		(fp_line
			(start -1.184656 2.0574)
			(end -0.796544 2.0574)
			(stroke
				(width 0.0127)
				(type default)
			)
			(layer "F.SilkS")
		)
		(fp_line
			(start -1.175258 2.048002)
			(end -0.806196 2.048002)
			(stroke
				(width 0.0127)
				(type default)
			)
			(layer "F.SilkS")
		)
		(fp_line
			(start -1.165606 2.03835)
			(end -0.815594 2.03835)
			(stroke
				(width 0.0127)
				(type default)
			)
			(layer "F.SilkS")
		)
		(fp_line
			(start -1.156208 2.028952)
			(end -0.825246 2.028952)
			(stroke
				(width 0.0127)
				(type default)
			)
			(layer "F.SilkS")
		)
		(fp_line
			(start -1.146556 2.0193)
			(end -0.834644 2.0193)
			(stroke
				(width 0.0127)
				(type default)
			)
			(layer "F.SilkS")
		)
		(fp_line
			(start -1.137158 2.009902)
			(end -0.844296 2.009902)
			(stroke
				(width 0.0127)
				(type default)
			)
			(layer "F.SilkS")
		)
		(fp_line
			(start -1.127506 2.00025)
			(end -0.853694 2.00025)
			(stroke
				(width 0.0127)
				(type default)
			)
			(layer "F.SilkS")
		)
		(fp_line
			(start -1.118108 1.990852)
			(end -0.863346 1.990852)
			(stroke
				(width 0.0127)
				(type default)
			)
			(layer "F.SilkS")
		)
		(fp_line
			(start -1.108456 1.9812)
			(end -0.872744 1.9812)
			(stroke
				(width 0.0127)
				(type default)
			)
			(layer "F.SilkS")
		)
		(fp_line
			(start -1.099058 1.971802)
			(end -0.882396 1.971802)
			(stroke
				(width 0.0127)
				(type default)
			)
			(layer "F.SilkS")
		)
		(fp_line
			(start -1.089406 1.96215)
			(end -0.891794 1.96215)
			(stroke
				(width 0.0127)
				(type default)
			)
			(layer "F.SilkS")
		)
		(fp_line
			(start -1.080008 1.952752)
			(end -0.901446 1.952752)
			(stroke
				(width 0.0127)
				(type default)
			)
			(layer "F.SilkS")
		)
		(fp_line
			(start -1.070356 1.9431)
			(end -0.910844 1.9431)
			(stroke
				(width 0.0127)
				(type default)
			)
			(layer "F.SilkS")
		)
		(fp_line
			(start -1.060958 1.933702)
			(end -0.920496 1.933702)
			(stroke
				(width 0.0127)
				(type default)
			)
			(layer "F.SilkS")
		)
		(fp_line
			(start -1.051306 1.92405)
			(end -0.929894 1.92405)
			(stroke
				(width 0.0127)
				(type default)
			)
			(layer "F.SilkS")
		)
		(fp_line
			(start -1.041908 1.914652)
			(end -0.939546 1.914652)
			(stroke
				(width 0.0127)
				(type default)
			)
			(layer "F.SilkS")
		)
		(fp_line
			(start -1.032256 1.905)
			(end -0.948944 1.905)
			(stroke
				(width 0.0127)
				(type default)
			)
			(layer "F.SilkS")
		)
		(fp_line
			(start -1.022858 1.895602)
			(end -0.958596 1.895602)
			(stroke
				(width 0.0127)
				(type default)
			)
			(layer "F.SilkS")
		)
		(fp_line
			(start -1.013206 1.88595)
			(end -0.967994 1.88595)
			(stroke
				(width 0.0127)
				(type default)
			)
			(layer "F.SilkS")
		)
		(fp_line
			(start -1.003808 1.876552)
			(end -0.977646 1.876552)
			(stroke
				(width 0.0127)
				(type default)
			)
			(layer "F.SilkS")
		)
		(fp_line
			(start -0.994156 1.8669)
			(end -0.987044 1.8669)
			(stroke
				(width 0.0127)
				(type default)
			)
			(layer "F.SilkS")
		)
		(fp_line
			(start -0.9906 1.86309)
			(end -0.701294 2.15265)
			(stroke
				(width 0.0127)
				(type default)
			)
			(layer "F.SilkS")
		)
		(fp_line
			(start -0.719074 2.145538)
			(end -1.265936 2.14122)
			(stroke
				(width 0.0127)
				(type default)
			)
			(layer "F.SilkS")
		)
		(fp_line
			(start -0.71628 2.15265)
			(end -1.26492 2.15265)
			(stroke
				(width 0.0127)
				(type default)
			)
			(layer "F.SilkS")
		)
		(fp_line
			(start -0.635 1.8796)
			(end -1.7526 1.8796)
			(stroke
				(width 0.3302)
				(type default)
			)
			(layer "F.SilkS")
		)
		(fp_line
			(start 1.651 -1.778)
			(end -1.651 -1.778)
			(stroke
				(width 0.1524)
				(type default)
			)
			(layer "F.SilkS")
		)
		(fp_line
			(start 1.651 1.778)
			(end 1.651 -1.778)
			(stroke
				(width 0.1524)
				(type default)
			)
			(layer "F.SilkS")
		)
		(fp_poly
			(pts
				(xy -1.285748 2.159) (xy -1.285748 1.8796) (xy -1.778 1.8796) (xy -1.778 -1.8796) (xy 1.778 -1.8796)
				(xy 1.778 1.8796) (xy -0.694944 1.8796) (xy -0.694944 2.159)
			)
			(stroke
				(width 0)
				(type default)
			)
			(fill no)
			(layer "F.CrtYd")
		)
		(fp_poly
			(pts
				(xy -1.285748 2.159) (xy -1.285748 1.8796) (xy -1.778 1.8796) (xy -1.778 -1.8796) (xy 1.778 -1.8796)
				(xy 1.778 1.8796) (xy -0.694944 1.8796) (xy -0.694944 2.159)
			)
			(stroke
				(width 0)
				(type default)
			)
			(fill no)
			(layer "F.Fab")
		)
		(pad "1" smd rect
			(at -0.98425 0.9525)
			(size 0.762 1.143)
			(layers "F.Cu" "F.Mask" "F.Paste")
			(net "OTP_RETRY_B")
		)
		(pad "2" smd rect
			(at 0.98425 0.9525)
			(size 0.762 1.143)
			(layers "F.Cu" "F.Mask" "F.Paste")
			(net "GND")
		)
		(pad "3" smd rect
			(at 0 -0.9525)
			(size 0.762 1.143)
			(layers "F.Cu" "F.Mask" "F.Paste")
			(net "OTP_RETRY_C")
		)
	)
)
